# S9S_MB_2U (Grand Teton) — schematic netlist excerpt (pin names and nets, part order shuffled) for the footprints in the layout excerpt that follows; sources: Cadence DE-HDL packaged netlist, KiCad conversion of 03242023_DA0F0TMBIJ0_F0T_Motherboard_J_brd_V01_OCP.brd

J13  SCONN288_ADR50017P130CC  SCONN288_ADR50017-P130CC IO  pkg DDR288S_1-1VXB  page 94
  VIN_BULK0  = P12V_S3_AUX_CPU0_NVDIMM
  RFU0  = TP_CHG_CPU0_DIMM1_FRU_0
  VIN_MGMT  = P3V3_AUX
  HSCL  = I3C_SPD_DDREFGH_CPU0_LVC1_SCL_4
  HSDA  = I3C_SPD_DDREFGH_CPU0_LVC1_SDA
  VSS0  = GND
  DQ0_A  = M_G_CPU0_SA_DQ<0>
  VSS1  = GND
  DQ1_A  = M_G_CPU0_SA_DQ<1>
  VSS2  = GND
  DQS0_A_T  = M_G_CPU0_SA_DQS_DP<0>
  DQS0_A_C  = M_G_CPU0_SA_DQS_DN<0>
  VSS3  = GND
  DQ4_A  = M_G_CPU0_SA_DQ<4>
  VSS4  = GND
  DQ5_A  = M_G_CPU0_SA_DQ<5>
  VSS5  = GND
  DQ8_A  = M_G_CPU0_SA_DQ<8>
  VSS6  = GND
  DQ9_A  = M_G_CPU0_SA_DQ<9>
  VSS7  = GND
  DQS1_A_T  = M_G_CPU0_SA_DQS_DP<1>
  DQS1_A_C  = M_G_CPU0_SA_DQS_DN<1>
  VSS8  = GND
  DQ12_A  = M_G_CPU0_SA_DQ<12>
  VSS9  = GND
  DQ13_A  = M_G_CPU0_SA_DQ<13>
  VSS10  = GND
  DQ16_A  = M_G_CPU0_SA_DQ<16>
  VSS11  = GND
  DQ17_A  = M_G_CPU0_SA_DQ<17>
  VSS12  = GND
  DQS2_A_T  = M_G_CPU0_SA_DQS_DP<2>
  DQS2_A_C  = M_G_CPU0_SA_DQS_DN<2>
  VSS13  = GND
  DQ20_A  = M_G_CPU0_SA_DQ<20>
  VSS14  = GND
  DQ21_A  = M_G_CPU0_SA_DQ<21>
  VSS15  = GND
  DQ24_A  = M_G_CPU0_SA_DQ<24>
  VSS16  = GND
  DQ25_A  = M_G_CPU0_SA_DQ<25>
  VSS17  = GND
  DQS3_A_T  = M_G_CPU0_SA_DQS_DP<3>
  DQS3_A_C  = M_G_CPU0_SA_DQS_DN<3>
  VSS18  = GND
  DQ28_A  = M_G_CPU0_SA_DQ<28>
  VSS19  = GND
  DQ29_A  = M_G_CPU0_SA_DQ<29>
  VSS20  = GND
  CB0_A  = M_G_CPU0_SA_CB<0>
  VSS21  = GND
  CB1_A  = M_G_CPU0_SA_CB<1>
  VSS22  = GND
  DQS4_A_T  = M_G_CPU0_SA_DQS_DP<4>
  DQS4_A_C  = M_G_CPU0_SA_DQS_DN<4>
  VSS23  = GND
  CB4_A  = M_G_CPU0_SA_CB<4>
  VSS24  = GND
  CB5_A  = M_G_CPU0_SA_CB<5>
  VSS25  = GND
  ALERT_N  = M_G_CPU0_ALERT_N
  VSS26  = GND
  CS0_A_N  = M_G_CPU0_SA_CS_N<0>
  VSS27  = GND
  CA0_A  = M_G_CPU0_SA_CA<0>
  VSS28  = GND
  CA2_A  = M_G_CPU0_SA_CA<2>
  VSS29  = GND
  CA4_A  = M_G_CPU0_SA_CA<4>
  VSS30  = GND
  CA6_A  = M_G_CPU0_SA_CA<6>
  VSS31  = GND
  PAR_A  = M_G_CPU0_SA_PAR
  VSS32  = GND
  CA0_B  = M_G_CPU0_SB_CA<0>
  VSS33  = GND
  CA2_B  = M_G_CPU0_SB_CA<2>
  VSS34  = GND
  CA4_B  = M_G_CPU0_SB_CA<4>
  VSS35  = GND
  CA6_B  = M_G_CPU0_SB_CA<6>
  VSS36  = GND
  CS0_B_N  = M_G_CPU0_SB_CS_N<0>
  VSS37  = GND
  \lbd||rsp_a_n\  = M_G_CPU0_SA_RSP<0>
  \lbs||rsp_b_n\  = M_G_CPU0_SB_RSP<0>
  VSS38  = GND
  CB4_B  = M_G_CPU0_SB_CB<4>
  VSS39  = GND
  CB5_B  = M_G_CPU0_SB_CB<5>
  VSS40  = GND
  \dqs9_b_t||tdqs9_b_t||dbi4_b_n\  = M_G_CPU0_SB_DQS_DP<9>
  \dqs9_b_c||tdqs9_b_c\  = M_G_CPU0_SB_DQS_DN<9>
  VSS41  = GND
  CB0_B  = M_G_CPU0_SB_CB<0>
  VSS42  = GND
  CB1_B  = M_G_CPU0_SB_CB<1>
  VSS43  = GND
  DQ0_B  = M_G_CPU0_SB_DQ<0>
  VSS44  = GND
  DQ1_B  = M_G_CPU0_SB_DQ<1>
  VSS45  = GND
  DQS0_B_T  = M_G_CPU0_SB_DQS_DP<0>
  DQS0_B_C  = M_G_CPU0_SB_DQS_DN<0>
  VSS46  = GND
  DQ4_B  = M_G_CPU0_SB_DQ<4>
  VSS47  = GND
  DQ5_B  = M_G_CPU0_SB_DQ<5>
  VSS48  = GND
  DQ8_B  = M_G_CPU0_SB_DQ<8>
  VSS49  = GND
  DQ9_B  = M_G_CPU0_SB_DQ<9>
  VSS50  = GND
  DQS1_B_T  = M_G_CPU0_SB_DQS_DP<1>
  DQS1_B_C  = M_G_CPU0_SB_DQS_DN<1>
  VSS51  = GND
  DQ12_B  = M_G_CPU0_SB_DQ<12>
  VSS52  = GND
  DQ13_B  = M_G_CPU0_SB_DQ<13>
  VSS53  = GND
  DQ16_B  = M_G_CPU0_SB_DQ<16>
  VSS54  = GND
  DQ17_B  = M_G_CPU0_SB_DQ<17>
  VSS55  = GND
  DQS2_B_T  = M_G_CPU0_SB_DQS_DP<2>
  DQS2_B_C  = M_G_CPU0_SB_DQS_DN<2>
  VSS56  = GND
  DQ20_B  = M_G_CPU0_SB_DQ<20>
  VSS57  = GND
  DQ21_B  = M_G_CPU0_SB_DQ<21>
  VSS58  = GND
  DQ24_B  = M_G_CPU0_SB_DQ<24>
  VSS59  = GND
  DQ25_B  = M_G_CPU0_SB_DQ<25>
  VSS60  = GND
  DQS3_B_T  = M_G_CPU0_SB_DQS_DP<3>
  DQS3_B_C  = M_G_CPU0_SB_DQS_DN<3>
  VSS61  = GND
  DQ28_B  = M_G_CPU0_SB_DQ<28>
  VSS62  = GND
  DQ29_B  = M_G_CPU0_SB_DQ<29>
  VSS63  = GND
  RFU1  = TP_CHG_CPU0_DIMM1_FRU_1
  VIN_BULK1  = P12V_S3_AUX_CPU0_NVDIMM
  VIN_BULK2  = P12V_S3_AUX_CPU0_NVDIMM
  \pwr_good||fail_n\  = PWRGD_CHG_CPU0_DIMM1
  HSA  = PD_CHG_CPU0_DIMM1_SAA
  RFU2  = TP_CHG_CPU0_DIMM1_FRU_2
  RFU3  = TP_CHG_CPU0_DIMM1_FRU_3
  VSS64  = GND
  DQ2_A  = M_G_CPU0_SA_DQ<2>
  VSS65  = GND
  DQ3_A  = M_G_CPU0_SA_DQ<3>
  VSS66  = GND
  \dqs5_a_c||tdqs5_a_c||dqs5_a_t||tdqs5_a_t\  = M_G_CPU0_SA_DQS_DN<5>
  \dqs5_a_t||tdqs5_a_t\  = M_G_CPU0_SA_DQS_DP<5>
  VSS67  = GND
  DQ6_A  = M_G_CPU0_SA_DQ<6>
  VSS68  = GND
  DQ7_A  = M_G_CPU0_SA_DQ<7>
  VSS69  = GND
  DQ10_A  = M_G_CPU0_SA_DQ<10>
  VSS70  = GND
  DQ11_A  = M_G_CPU0_SA_DQ<11>
  VSS71  = GND
  \dqs6_a_c||tdqs6_a_c||dqs6_a_t||tdqs6_a_t\  = M_G_CPU0_SA_DQS_DN<6>
  \dqs6_a_t||tdqs6_a_t\  = M_G_CPU0_SA_DQS_DP<6>
  VSS72  = GND
  DQ14_A  = M_G_CPU0_SA_DQ<14>
  VSS73  = GND
  DQ15_A  = M_G_CPU0_SA_DQ<15>
  VSS74  = GND
  DQ18_A  = M_G_CPU0_SA_DQ<18>
  VSS75  = GND
  DQ19_A  = M_G_CPU0_SA_DQ<19>
  VSS76  = GND
  \dqs7_a_c||tdqs7_a_c\  = M_G_CPU0_SA_DQS_DN<7>
  \dqs7_a_t||tdqs7_a_t\  = M_G_CPU0_SA_DQS_DP<7>
  VSS77  = GND
  DQ22_A  = M_G_CPU0_SA_DQ<22>
  VSS78  = GND
  DQ23_A  = M_G_CPU0_SA_DQ<23>
  VSS79  = GND
  DQ26_A  = M_G_CPU0_SA_DQ<26>
  VSS80  = GND
  DQ27_A  = M_G_CPU0_SA_DQ<27>
  VSS81  = GND
  \dqs8_a_c||tdqs8_a_c\  = M_G_CPU0_SA_DQS_DN<8>
  \dqs8_a_t||tdqs8_a_t\  = M_G_CPU0_SA_DQS_DP<8>
  VSS82  = GND
  DQ30_A  = M_G_CPU0_SA_DQ<30>
  VSS83  = GND
  DQ31_A  = M_G_CPU0_SA_DQ<31>
  VSS84  = GND
  CB2_A  = M_G_CPU0_SA_CB<2>
  VSS85  = GND
  CB3_A  = M_G_CPU0_SA_CB<3>
  VSS86  = GND
  \dqs9_a_c||tdqs9_a_c\  = M_G_CPU0_SA_DQS_DN<9>
  \dqs9_a_t||tdqs9_a_t\  = M_G_CPU0_SA_DQS_DP<9>
  VSS87  = GND
  CB6_A  = M_G_CPU0_SA_CB<6>
  VSS88  = GND
  CB7_A  = M_G_CPU0_SA_CB<7>
  VSS89  = GND
  RESET_N  = RST_M_GH_CPU0_FPGA_N
  VSS90  = GND
  CS1_A_N  = M_G_CPU0_SA_CS_N<1>
  VSS91  = GND
  CA1_A  = M_G_CPU0_SA_CA<1>
  VSS92  = GND
  CA3_A  = M_G_CPU0_SA_CA<3>
  VSS93  = GND
  CA5_A  = M_G_CPU0_SA_CA<5>
  VSS94  = GND
  CK_T  = M_G_CPU0_CLK_DP<0>
  CK_C  = M_G_CPU0_CLK_DN<0>
  VSS95  = GND
  RFU4  = TP_CHG_CPU0_DIMM1_FRU_4
  CA1_B  = M_G_CPU0_SB_CA<1>
  VSS96  = GND
  CA3_B  = M_G_CPU0_SB_CA<3>
  VSS97  = GND
  CA5_B  = M_G_CPU0_SB_CA<5>
  VSS98  = GND
  PAR_B  = M_G_CPU0_SB_PAR
  VSS99  = GND
  CS1_B_N  = M_G_CPU0_SB_CS_N<1>
  VSS100  = GND
  RFU5  = TP_CHG_CPU0_DIMM1_FRU_5
  RFU6  = TP_CHG_CPU0_DIMM1_FRU_6
  VSS101  = GND
  CB6_B  = M_G_CPU0_SB_CB<6>
  VSS102  = GND
  CB7_B  = M_G_CPU0_SB_CB<7>
  VSS103  = GND
  DQS4_B_C  = M_G_CPU0_SB_DQS_DN<4>
  DQS4_B_T  = M_G_CPU0_SB_DQS_DP<4>
  VSS104  = GND
  CB2_B  = M_G_CPU0_SB_CB<2>
  VSS105  = GND
  CB3_B  = M_G_CPU0_SB_CB<3>
  VSS106  = GND
  DQ2_B  = M_G_CPU0_SB_DQ<2>
  VSS107  = GND
  DQ3_B  = M_G_CPU0_SB_DQ<3>
  VSS108  = GND
  \dqs5_b_c||tdqs5_b_c\  = M_G_CPU0_SB_DQS_DN<5>
  \dqs5_b_t||tdqs5_b_t\  = M_G_CPU0_SB_DQS_DP<5>
  VSS109  = GND
  DQ6_B  = M_G_CPU0_SB_DQ<6>
  VSS110  = GND
  DQ7_B  = M_G_CPU0_SB_DQ<7>
  VSS111  = GND
  DQ10_B  = M_G_CPU0_SB_DQ<10>
  VSS112  = GND
  DQ11_B  = M_G_CPU0_SB_DQ<11>
  VSS113  = GND
  \dqs6_b_c||tdqs6_b_c\  = M_G_CPU0_SB_DQS_DN<6>
  \dqs6_b_t||tdqs6_b_t\  = M_G_CPU0_SB_DQS_DP<6>
  VSS114  = GND
  DQ14_B  = M_G_CPU0_SB_DQ<14>
  VSS115  = GND
  DQ15_B  = M_G_CPU0_SB_DQ<15>
  VSS116  = GND
  DQ18_B  = M_G_CPU0_SB_DQ<18>
  VSS117  = GND
  DQ19_B  = M_G_CPU0_SB_DQ<19>
  VSS118  = GND
  \dqs7_b_c||tdqs7_b_c\  = M_G_CPU0_SB_DQS_DN<7>
  \dqs7_b_t||tdqs7_b_t\  = M_G_CPU0_SB_DQS_DP<7>
  VSS119  = GND
  DQ22_B  = M_G_CPU0_SB_DQ<22>
  VSS120  = GND
  DQ23_B  = M_G_CPU0_SB_DQ<23>
  VSS121  = GND
  DQ26_B  = M_G_CPU0_SB_DQ<26>
  VSS122  = GND
  DQ27_B  = M_G_CPU0_SB_DQ<27>
  VSS123  = GND
  \dqs8_b_c||tdqs8_b_c\  = M_G_CPU0_SB_DQS_DN<8>
  \dqs8_b_t||tdqs8_b_t\  = M_G_CPU0_SB_DQS_DP<8>
  VSS124  = GND
  DQ30_B  = M_G_CPU0_SB_DQ<30>
  VSS125  = GND
  DQ31_B  = M_G_CPU0_SB_DQ<31>
  VSS126  = GND
  G1  = GND
  G2  = GND
  G3  = GND

(kicad_pcb
	(version 20260206)
	(generator "pcbnew")
	(generator_version "10.0")
	(general
		(thickness 1.6)
		(legacy_teardrops no)
	)
	(paper "A4")
	(title_block
		(title "03242023_DA0F0TMBIJ0_F0T_Motherboard_J_brd_V01_OCP.brd")
		(comment 1 "Grand Teton / footprint 1368 of 6105 (J13), pads 1-45 of 291")
	)
	(layers
		(0 "F.Cu" signal "TOP")
		(4 "In1.Cu" signal "GND")
		(6 "In2.Cu" signal "IN1")
		(8 "In3.Cu" signal "GND1")
		(10 "In4.Cu" signal "IN2")
		(12 "In5.Cu" signal "GND2")
		(14 "In6.Cu" signal "IN3")
		(16 "In7.Cu" signal "GND3")
		(18 "In8.Cu" signal "VCC")
		(20 "In9.Cu" signal "VCC1")
		(22 "In10.Cu" signal "GND4")
		(24 "In11.Cu" signal "IN4")
		(26 "In12.Cu" signal "GND5")
		(28 "In13.Cu" signal "IN5")
		(30 "In14.Cu" signal "GND6")
		(32 "In15.Cu" signal "IN6")
		(34 "In16.Cu" signal "GND7")
		(2 "B.Cu" signal "BOTTOM")
		(9 "F.Adhes" user "F.Adhesive")
		(11 "B.Adhes" user "B.Adhesive")
		(13 "F.Paste" user "Package Geometry/Pastemask Top")
		(15 "B.Paste" user "Package Geometry/Pastemask Bottom")
		(5 "F.SilkS" user "Ref Des/Silkscreen Top")
		(7 "B.SilkS" user "Ref Des/Silkscreen Bottom")
		(1 "F.Mask" user "Board Geometry/Soldermask Top")
		(3 "B.Mask" user "Board Geometry/Soldermask Bottom")
		(17 "Dwgs.User" user "User.Drawings")
		(19 "Cmts.User" user "User.Comments")
		(21 "Eco1.User" user "User.Eco1")
		(23 "Eco2.User" user "User.Eco2")
		(25 "Edge.Cuts" user "Board Geometry/Outline")
		(27 "Margin" user)
		(31 "F.CrtYd" user "Package Geometry/Place Bound Top")
		(29 "B.CrtYd" user "Package Geometry/Place Bound Bottom")
		(35 "F.Fab" user "Ref Des/Assembly Top")
		(33 "B.Fab" user "Ref Des/Assembly Bottom")
	)
	(footprint ""
		(layer "F.Cu")
		(at 446.522348 -258.091686)
		(property "Reference" "J13"
			(at -3.683 -81.702148 0)
			(unlocked yes)
			(layer "F.SilkS")
			(effects
				(font
					(size 0.7874 0.5842)
					(thickness 0.1524)
				)
				(justify left)
			)
		)
		(property "Value" ""
			(at 0 0 0)
			(layer "F.Fab")
			(effects
				(font
					(size 1.27 1.27)
				)
			)
		)
		(duplicate_pad_numbers_are_jumpers no)
		(pad "1" smd rect
			(at -2.050034 -63.324994 270)
			(size 0.519938 1.4986)
			(layers "F.Cu" "F.Mask" "F.Paste")
			(net "P12V_S3_AUX_CPU0_NVDIMM")
		)
		(pad "2" smd rect
			(at -2.050034 -62.47511 270)
			(size 0.519938 1.4986)
			(layers "F.Cu" "F.Mask" "F.Paste")
			(net "TP_CHG_CPU0_DIMM1_FRU_0")
		)
		(pad "3" smd rect
			(at -2.050034 -61.624972 270)
			(size 0.519938 1.4986)
			(layers "F.Cu" "F.Mask" "F.Paste")
			(net "P3V3_AUX")
		)
		(pad "4" smd rect
			(at -2.050034 -60.775088 270)
			(size 0.519938 1.4986)
			(layers "F.Cu" "F.Mask" "F.Paste")
			(net "I3C_SPD_DDREFGH_CPU0_LVC1_SCL_4")
		)
		(pad "5" smd rect
			(at -2.050034 -59.92495 270)
			(size 0.519938 1.4986)
			(layers "F.Cu" "F.Mask" "F.Paste")
			(net "I3C_SPD_DDREFGH_CPU0_LVC1_SDA")
		)
		(pad "6" smd rect
			(at -2.050034 -59.075066 270)
			(size 0.519938 1.4986)
			(layers "F.Cu" "F.Mask" "F.Paste")
			(net "GND")
		)
		(pad "7" smd rect
			(at -2.050034 -58.224928 270)
			(size 0.519938 1.4986)
			(layers "F.Cu" "F.Mask" "F.Paste")
			(net "M_G_CPU0_SA_DQ<0>")
		)
		(pad "8" smd rect
			(at -2.050034 -57.375044 270)
			(size 0.519938 1.4986)
			(layers "F.Cu" "F.Mask" "F.Paste")
			(net "GND")
		)
		(pad "9" smd rect
			(at -2.050034 -56.524906 270)
			(size 0.519938 1.4986)
			(layers "F.Cu" "F.Mask" "F.Paste")
			(net "M_G_CPU0_SA_DQ<1>")
		)
		(pad "10" smd rect
			(at -2.050034 -55.675022 270)
			(size 0.519938 1.4986)
			(layers "F.Cu" "F.Mask" "F.Paste")
			(net "GND")
		)
		(pad "11" smd rect
			(at -2.050034 -54.824884 270)
			(size 0.519938 1.4986)
			(layers "F.Cu" "F.Mask" "F.Paste")
			(net "M_G_CPU0_SA_DQS_DP<0>")
		)
		(pad "12" smd rect
			(at -2.050034 -53.975 270)
			(size 0.519938 1.4986)
			(layers "F.Cu" "F.Mask" "F.Paste")
			(net "M_G_CPU0_SA_DQS_DN<0>")
		)
		(pad "13" smd rect
			(at -2.050034 -53.125116 270)
			(size 0.519938 1.4986)
			(layers "F.Cu" "F.Mask" "F.Paste")
			(net "GND")
		)
		(pad "14" smd rect
			(at -2.050034 -52.274978 270)
			(size 0.519938 1.4986)
			(layers "F.Cu" "F.Mask" "F.Paste")
			(net "M_G_CPU0_SA_DQ<4>")
		)
		(pad "15" smd rect
			(at -2.050034 -51.425094 270)
			(size 0.519938 1.4986)
			(layers "F.Cu" "F.Mask" "F.Paste")
			(net "GND")
		)
		(pad "16" smd rect
			(at -2.050034 -50.574956 270)
			(size 0.519938 1.4986)
			(layers "F.Cu" "F.Mask" "F.Paste")
			(net "M_G_CPU0_SA_DQ<5>")
		)
		(pad "17" smd rect
			(at -2.050034 -49.725072 270)
			(size 0.519938 1.4986)
			(layers "F.Cu" "F.Mask" "F.Paste")
			(net "GND")
		)
		(pad "18" smd rect
			(at -2.050034 -48.874934 270)
			(size 0.519938 1.4986)
			(layers "F.Cu" "F.Mask" "F.Paste")
			(net "M_G_CPU0_SA_DQ<8>")
		)
		(pad "19" smd rect
			(at -2.050034 -48.02505 270)
			(size 0.519938 1.4986)
			(layers "F.Cu" "F.Mask" "F.Paste")
			(net "GND")
		)
		(pad "20" smd rect
			(at -2.050034 -47.174912 270)
			(size 0.519938 1.4986)
			(layers "F.Cu" "F.Mask" "F.Paste")
			(net "M_G_CPU0_SA_DQ<9>")
		)
		(pad "21" smd rect
			(at -2.050034 -46.325028 270)
			(size 0.519938 1.4986)
			(layers "F.Cu" "F.Mask" "F.Paste")
			(net "GND")
		)
		(pad "22" smd rect
			(at -2.050034 -45.47489 270)
			(size 0.519938 1.4986)
			(layers "F.Cu" "F.Mask" "F.Paste")
			(net "M_G_CPU0_SA_DQS_DP<1>")
		)
		(pad "23" smd rect
			(at -2.050034 -44.625006 270)
			(size 0.519938 1.4986)
			(layers "F.Cu" "F.Mask" "F.Paste")
			(net "M_G_CPU0_SA_DQS_DN<1>")
		)
		(pad "24" smd rect
			(at -2.050034 -43.775122 270)
			(size 0.519938 1.4986)
			(layers "F.Cu" "F.Mask" "F.Paste")
			(net "GND")
		)
		(pad "25" smd rect
			(at -2.050034 -42.924984 270)
			(size 0.519938 1.4986)
			(layers "F.Cu" "F.Mask" "F.Paste")
			(net "M_G_CPU0_SA_DQ<12>")
		)
		(pad "26" smd rect
			(at -2.050034 -42.0751 270)
			(size 0.519938 1.4986)
			(layers "F.Cu" "F.Mask" "F.Paste")
			(net "GND")
		)
		(pad "27" smd rect
			(at -2.050034 -41.224962 270)
			(size 0.519938 1.4986)
			(layers "F.Cu" "F.Mask" "F.Paste")
			(net "M_G_CPU0_SA_DQ<13>")
		)
		(pad "28" smd rect
			(at -2.050034 -40.375078 270)
			(size 0.519938 1.4986)
			(layers "F.Cu" "F.Mask" "F.Paste")
			(net "GND")
		)
		(pad "29" smd rect
			(at -2.050034 -39.52494 270)
			(size 0.519938 1.4986)
			(layers "F.Cu" "F.Mask" "F.Paste")
			(net "M_G_CPU0_SA_DQ<16>")
		)
		(pad "30" smd rect
			(at -2.050034 -38.675056 270)
			(size 0.519938 1.4986)
			(layers "F.Cu" "F.Mask" "F.Paste")
			(net "GND")
		)
		(pad "31" smd rect
			(at -2.050034 -37.824918 270)
			(size 0.519938 1.4986)
			(layers "F.Cu" "F.Mask" "F.Paste")
			(net "M_G_CPU0_SA_DQ<17>")
		)
		(pad "32" smd rect
			(at -2.050034 -36.975034 270)
			(size 0.519938 1.4986)
			(layers "F.Cu" "F.Mask" "F.Paste")
			(net "GND")
		)
		(pad "33" smd rect
			(at -2.050034 -36.124896 270)
			(size 0.519938 1.4986)
			(layers "F.Cu" "F.Mask" "F.Paste")
			(net "M_G_CPU0_SA_DQS_DP<2>")
		)
		(pad "34" smd rect
			(at -2.050034 -35.275012 270)
			(size 0.519938 1.4986)
			(layers "F.Cu" "F.Mask" "F.Paste")
			(net "M_G_CPU0_SA_DQS_DN<2>")
		)
		(pad "35" smd rect
			(at -2.050034 -34.425128 270)
			(size 0.519938 1.4986)
			(layers "F.Cu" "F.Mask" "F.Paste")
			(net "GND")
		)
		(pad "36" smd rect
			(at -2.050034 -33.57499 270)
			(size 0.519938 1.4986)
			(layers "F.Cu" "F.Mask" "F.Paste")
			(net "M_G_CPU0_SA_DQ<20>")
		)
		(pad "37" smd rect
			(at -2.050034 -32.725106 270)
			(size 0.519938 1.4986)
			(layers "F.Cu" "F.Mask" "F.Paste")
			(net "GND")
		)
		(pad "38" smd rect
			(at -2.050034 -31.874968 270)
			(size 0.519938 1.4986)
			(layers "F.Cu" "F.Mask" "F.Paste")
			(net "M_G_CPU0_SA_DQ<21>")
		)
		(pad "39" smd rect
			(at -2.050034 -31.025084 270)
			(size 0.519938 1.4986)
			(layers "F.Cu" "F.Mask" "F.Paste")
			(net "GND")
		)
		(pad "40" smd rect
			(at -2.050034 -30.174946 270)
			(size 0.519938 1.4986)
			(layers "F.Cu" "F.Mask" "F.Paste")
			(net "M_G_CPU0_SA_DQ<24>")
		)
		(pad "41" smd rect
			(at -2.050034 -29.325062 270)
			(size 0.519938 1.4986)
			(layers "F.Cu" "F.Mask" "F.Paste")
			(net "GND")
		)
		(pad "42" smd rect
			(at -2.050034 -28.474924 270)
			(size 0.519938 1.4986)
			(layers "F.Cu" "F.Mask" "F.Paste")
			(net "M_G_CPU0_SA_DQ<25>")
		)
		(pad "43" smd rect
			(at -2.050034 -27.62504 270)
			(size 0.519938 1.4986)
			(layers "F.Cu" "F.Mask" "F.Paste")
			(net "GND")
		)
		(pad "44" smd rect
			(at -2.050034 -26.774902 270)
			(size 0.519938 1.4986)
			(layers "F.Cu" "F.Mask" "F.Paste")
			(net "M_G_CPU0_SA_DQS_DP<3>")
		)
		(pad "45" smd rect
			(at -2.050034 -25.925018 270)
			(size 0.519938 1.4986)
			(layers "F.Cu" "F.Mask" "F.Paste")
			(net "M_G_CPU0_SA_DQS_DN<3>")
		)
	)
)
